FILE_TYPE = CONNECTIVITY;
{Allegro Design Entry HDL 16.6-p007 (v16-6-112F) 10/10/2012}
"PAGE_NUMBER" = 132;
0"NC";
1"GND\g";
2"PVNN_PCH_STBY\g";
3"GND\g";
4"PVNN_PCH_STBY\g";
5"GND\g";
6"PVNN_PCH_STBY\g";
7"GND\g";
8"GND\g";
9"GND\g";
10"PVNN_PCH_STBY\g";
11"GND\g";
12"PVNN_PCH_STBY\g";
13"PVNN_PCH_STBY\g";
14"PVNN_PCH_STBY\g";
15"PVNN_PCH_STBY\g";
16"GND\g";
%"CAP_A"
"1","(2575,4475)","0","dev_discrete","I1";
;
ROOM"SB_DECOUPLING"
$SEC"1"
CDS_SEC"1"
CDS_LIB"dev_discrete"
BOM_COST"SB"
CDS_LOCATION"C3L25"
MATERIAL"X6S"
VOLTAGE"4V"
PACK_TYPE"0603V"
TOLERANCE"20%"
VALUE"22.0UF"
PART_NUMBER"E15431-004"
LOCATION"C3L25";
"B"
$PN"2"1;
"A"
$PN"1"13;
%"GND"
"1","(2050,4150)","0","mstr_symbols","I10";
;
HDL_POWER"GND"
ROOM"SB_DECOUPLING"
BODY_TYPE"PLUMBING"
CDS_LIB"mstr_symbols"
SIZE"1B"
BOM_COST"SB"
VOLTAGE"0.0V";
"A\NAC"1;
%"CAP_A"
"1","(2200,3500)","0","dev_discrete","I11";
;
ROOM"SB_DECOUPLING"
$SEC"1"
CDS_SEC"1"
CDS_LIB"dev_discrete"
BOM_COST"SB"
CDS_LOCATION"C7A36"
MATERIAL"X6S"
VOLTAGE"4V"
PACK_TYPE"0603V"
TOLERANCE"20%"
VALUE"22.0UF"
PART_NUMBER"E15431-004"
LOCATION"C7A36";
"B"
$PN"2"3;
"A"
$PN"1"2;
%"CAP_A"
"1","(1825,3500)","0","dev_discrete","I12";
;
ROOM"SB_DECOUPLING"
$SEC"1"
CDS_SEC"1"
CDS_LIB"dev_discrete"
BOM_COST"SB"
CDS_LOCATION"C3N12"
MATERIAL"X6S"
VOLTAGE"4V"
PACK_TYPE"0603V"
TOLERANCE"20%"
VALUE"22.0UF"
PART_NUMBER"E15431-004"
LOCATION"C3N12";
"B"
$PN"2"3;
"A"
$PN"1"2;
%"CAP_A"
"1","(1450,3500)","0","dev_discrete","I13";
;
ROOM"SB_DECOUPLING"
$SEC"1"
CDS_SEC"1"
CDS_LIB"dev_discrete"
BOM_COST"SB"
CDS_LOCATION"C3N10"
MATERIAL"X6S"
VOLTAGE"4V"
PACK_TYPE"0603V"
TOLERANCE"20%"
VALUE"22.0UF"
PART_NUMBER"E15431-004"
LOCATION"C3N10";
"B"
$PN"2"3;
"A"
$PN"1"2;
%"PVNN_PCH_STBY"
"1","(1350,3750)","0","mstr_symbols","I14";
;
HDL_POWER"PVNN_PCH_STBY"
ROOM"SB_DECOUPLING"
BODY_TYPE"PLUMBING"
BOM_COST"SB"
CDS_LIB"mstr_symbols"
VOLTAGE"1.0V";
"G\NAC"2;
%"GND"
"1","(2075,3175)","0","mstr_symbols","I15";
;
HDL_POWER"GND"
ROOM"SB_DECOUPLING"
BODY_TYPE"PLUMBING"
BOM_COST"SB"
SIZE"1B"
CDS_LIB"mstr_symbols"
VOLTAGE"0";
"A\NAC"3;
%"CAP_A"
"1","(1850,2525)","0","dev_discrete","I16";
;
ROOM"SB_DECOUPLING"
$SEC"1"
CDS_SEC"1"
CDS_LIB"dev_discrete"
BOM_COST"SB"
CDS_LOCATION"C3N24"
MATERIAL"X6S"
VOLTAGE"4V"
PACK_TYPE"0603V"
TOLERANCE"20%"
VALUE"22.0UF"
PART_NUMBER"E15431-004"
LOCATION"C3N24";
"B"
$PN"2"5;
"A"
$PN"1"4;
%"CAP_A"
"1","(1475,2525)","0","dev_discrete","I17";
;
ROOM"SB_DECOUPLING"
$SEC"1"
CDS_SEC"1"
CDS_LIB"dev_discrete"
BOM_COST"SB"
CDS_LOCATION"C3N28"
MATERIAL"X6S"
VOLTAGE"4V"
PACK_TYPE"0603V"
TOLERANCE"20%"
VALUE"22.0UF"
PART_NUMBER"E15431-004"
LOCATION"C3N28";
"B"
$PN"2"5;
"A"
$PN"1"4;
%"PVNN_PCH_STBY"
"1","(1400,2775)","0","mstr_symbols","I18";
;
HDL_POWER"PVNN_PCH_STBY"
ROOM"SB_DECOUPLING"
BODY_TYPE"PLUMBING"
BOM_COST"SB"
CDS_LIB"mstr_symbols"
VOLTAGE"1.0V";
"G\NAC"4;
%"CAP_A"
"1","(1075,3500)","0","dev_discrete","I19";
;
ROOM"SB_DECOUPLING"
$SEC"1"
CDS_SEC"1"
CDS_LIB"dev_discrete"
BOM_COST"SB"
CDS_LOCATION"C3N11"
MATERIAL"X6S"
VOLTAGE"4V"
PACK_TYPE"0603V"
TOLERANCE"20%"
VALUE"22.0UF"
PART_NUMBER"E15431-004"
LOCATION"C3N11";
"B"
$PN"2"3;
"A"
$PN"1"2;
%"CAP_A"
"1","(2200,4475)","0","dev_discrete","I2";
;
ROOM"SB_DECOUPLING"
$SEC"1"
CDS_SEC"1"
CDS_LIB"dev_discrete"
BOM_COST"SB"
CDS_LOCATION"C3M7"
MATERIAL"X6S"
VOLTAGE"4V"
PACK_TYPE"0603V"
TOLERANCE"20%"
VALUE"22.0UF"
PART_NUMBER"E15431-004"
LOCATION"C3M7";
"B"
$PN"2"1;
"A"
$PN"1"13;
%"CAP_A"
"1","(1100,2525)","0","dev_discrete","I20";
;
ROOM"SB_DECOUPLING"
$SEC"1"
CDS_SEC"1"
CDS_LIB"dev_discrete"
BOM_COST"SB"
CDS_LOCATION"C3N31"
MATERIAL"X6S"
VOLTAGE"4V"
PACK_TYPE"0603V"
TOLERANCE"20%"
VALUE"22.0UF"
PART_NUMBER"E15431-004"
LOCATION"C3N31";
"B"
$PN"2"5;
"A"
$PN"1"4;
%"GND"
"1","(2050,2200)","0","mstr_symbols","I21";
;
HDL_POWER"GND"
ROOM"SB_DECOUPLING"
BODY_TYPE"PLUMBING"
SIZE"1B"
CDS_LIB"mstr_symbols"
BOM_COST"SB"
VOLTAGE"0";
"A\NAC"5;
%"PVNN_PCH_STBY"
"1","(1925,1875)","0","mstr_symbols","I22";
;
HDL_POWER"PVNN_PCH_STBY"
ROOM"SB_DECOUPLING"
BODY_TYPE"PLUMBING"
BOM_COST"SB"
CDS_LIB"mstr_symbols"
VOLTAGE"1.0V";
"G\NAC"6;
%"CAP"
"1","(2150,1575)","0","mstr_discrete","I23";
;
ROOM"SB_DECOUPLING"
CDS_LOCATION"C7A33"
$SEC"1"
CDS_SEC"1"
BOM_COST"SB"
CDS_LIB"mstr_discrete"
MATERIAL"X6S"
VOLTAGE"4V"
PACK_TYPE"0805"
TOLERANCE"20%"
VALUE"47UF"
PART_NUMBER"C95333-006"
LOCATION"C7A33";
"A"
$PN"1"6;
"B"
$PN"2"7;
%"CAP"
"1","(1700,1575)","0","mstr_discrete","I24";
;
ROOM"SB_DECOUPLING"
CDS_LOCATION"C7B4"
$SEC"1"
CDS_SEC"1"
BOM_COST"SB"
CDS_LIB"mstr_discrete"
MATERIAL"X6S"
VOLTAGE"4V"
PACK_TYPE"0805"
TOLERANCE"20%"
VALUE"47UF"
PART_NUMBER"C95333-006"
LOCATION"C7B4";
"A"
$PN"1"6;
"B"
$PN"2"7;
%"GND"
"1","(1925,1200)","0","mstr_symbols","I25";
;
HDL_POWER"GND"
ROOM"SB_DECOUPLING"
BODY_TYPE"PLUMBING"
SIZE"1B"
CDS_LIB"mstr_symbols"
BOM_COST"SB"
VOLTAGE"0.0V";
"A\NAC"7;
%"CAP_A"
"1","(-325,4050)","0","dev_discrete","I26";
;
ROOM"SB_DECOUPLING"
$SEC"1"
CDS_SEC"1"
CDS_LIB"dev_discrete"
CDS_LOCATION"C2N9"
MATERIAL"X6S"
VOLTAGE"6.3V"
PACK_TYPE"0402V"
TOLERANCE"10%"
VALUE"1.0UF"
PART_NUMBER"D97712-004"
LOCATION"C2N9";
"B"
$PN"2"8;
"A"
$PN"1"12;
%"CAP_A"
"1","(-725,4050)","0","dev_discrete","I27";
;
ROOM"SB_DECOUPLING"
$SEC"1"
CDS_SEC"1"
CDS_LIB"dev_discrete"
BOM_COST"SB"
CDS_LOCATION"C2N3"
MATERIAL"X6S"
VOLTAGE"6.3V"
PACK_TYPE"0402V"
TOLERANCE"10%"
VALUE"1.0UF"
PART_NUMBER"D97712-004"
LOCATION"C2N3";
"B"
$PN"2"8;
"A"
$PN"1"12;
%"CAP_A"
"1","(-300,3025)","0","dev_discrete","I28";
;
ROOM"SB_DECOUPLING"
$SEC"1"
CDS_SEC"1"
CDS_LIB"dev_discrete"
CDS_LOCATION"C2N4"
MATERIAL"X6S"
VOLTAGE"6.3V"
PACK_TYPE"0402V"
TOLERANCE"10%"
VALUE"1.0UF"
PART_NUMBER"D97712-004"
LOCATION"C2N4";
"B"
$PN"2"9;
"A"
$PN"1"14;
%"CAP_A"
"1","(-700,3025)","0","dev_discrete","I29";
;
ROOM"SB_DECOUPLING"
$SEC"1"
CDS_SEC"1"
CDS_LIB"dev_discrete"
BOM_COST"SB"
CDS_LOCATION"C2N12"
MATERIAL"X6S"
VOLTAGE"6.3V"
PACK_TYPE"0402V"
TOLERANCE"10%"
VALUE"1.0UF"
PART_NUMBER"D97712-004"
LOCATION"C2N12";
"B"
$PN"2"9;
"A"
$PN"1"14;
%"CAP_A"
"1","(1825,4475)","0","dev_discrete","I3";
;
ROOM"SB_DECOUPLING"
$SEC"1"
CDS_SEC"1"
CDS_LIB"dev_discrete"
BOM_COST"SB"
CDS_LOCATION"C3L26"
MATERIAL"X6S"
VOLTAGE"4V"
PACK_TYPE"0603V"
TOLERANCE"20%"
VALUE"22.0UF"
PART_NUMBER"E15431-004"
LOCATION"C3L26";
"B"
$PN"2"1;
"A"
$PN"1"13;
%"CAP_A"
"1","(-1100,4050)","0","dev_discrete","I30";
;
ROOM"SB_DECOUPLING"
$SEC"1"
CDS_SEC"1"
CDS_LIB"dev_discrete"
BOM_COST"SB"
CDS_LOCATION"C2N11"
MATERIAL"X6S"
VOLTAGE"6.3V"
PACK_TYPE"0402V"
TOLERANCE"10%"
VALUE"1.0UF"
PART_NUMBER"D97712-004"
LOCATION"C2N11";
"B"
$PN"2"8;
"A"
$PN"1"12;
%"CAP_A"
"1","(-1475,4050)","0","dev_discrete","I31";
;
ROOM"SB_DECOUPLING"
$SEC"1"
CDS_SEC"1"
CDS_LIB"dev_discrete"
BOM_COST"SB"
CDS_LOCATION"C3N19"
MATERIAL"X6S"
VOLTAGE"6.3V"
PACK_TYPE"0402V"
TOLERANCE"10%"
VALUE"1.0UF"
PART_NUMBER"D97712-004"
LOCATION"C3N19";
"B"
$PN"2"8;
"A"
$PN"1"12;
%"CAP_A"
"1","(-1850,4050)","0","dev_discrete","I32";
;
ROOM"SB_DECOUPLING"
$SEC"1"
CDS_SEC"1"
CDS_LIB"dev_discrete"
BOM_COST"SB"
CDS_LOCATION"C3N3"
MATERIAL"X6S"
VOLTAGE"6.3V"
PACK_TYPE"0402V"
TOLERANCE"10%"
VALUE"1.0UF"
PART_NUMBER"D97712-004"
LOCATION"C3N3";
"B"
$PN"2"8;
"A"
$PN"1"12;
%"GND"
"1","(-1750,3750)","0","mstr_symbols","I33";
;
HDL_POWER"GND"
ROOM"SB_DECOUPLING"
BODY_TYPE"PLUMBING"
BOM_COST"SB"
CDS_LIB"mstr_symbols"
SIZE"1B"
VOLTAGE"0";
"A\NAC"8;
%"CAP_A"
"1","(-1075,3025)","0","dev_discrete","I34";
;
ROOM"SB_DECOUPLING"
$SEC"1"
CDS_SEC"1"
CDS_LIB"dev_discrete"
BOM_COST"SB"
CDS_LOCATION"C3N1"
MATERIAL"X6S"
VOLTAGE"6.3V"
PACK_TYPE"0402V"
TOLERANCE"10%"
VALUE"1.0UF"
PART_NUMBER"D97712-004"
LOCATION"C3N1";
"B"
$PN"2"9;
"A"
$PN"1"14;
%"CAP_A"
"1","(-1450,3025)","0","dev_discrete","I35";
;
ROOM"SB_DECOUPLING"
$SEC"1"
CDS_SEC"1"
CDS_LIB"dev_discrete"
BOM_COST"SB"
CDS_LOCATION"C3N7"
MATERIAL"X6S"
VOLTAGE"6.3V"
PACK_TYPE"0402V"
TOLERANCE"10%"
VALUE"1.0UF"
PART_NUMBER"D97712-004"
LOCATION"C3N7";
"B"
$PN"2"9;
"A"
$PN"1"14;
%"CAP_A"
"1","(-1825,3025)","0","dev_discrete","I36";
;
ROOM"SB_DECOUPLING"
$SEC"1"
CDS_SEC"1"
CDS_LIB"dev_discrete"
BOM_COST"SB"
CDS_LOCATION"C3N16"
MATERIAL"X6S"
VOLTAGE"6.3V"
PACK_TYPE"0402V"
TOLERANCE"10%"
VALUE"1.0UF"
PART_NUMBER"D97712-004"
LOCATION"C3N16";
"B"
$PN"2"9;
"A"
$PN"1"14;
%"GND"
"1","(-1725,2725)","0","mstr_symbols","I37";
;
HDL_POWER"GND"
ROOM"SB_DECOUPLING"
BODY_TYPE"PLUMBING"
BOM_COST"SB"
CDS_LIB"mstr_symbols"
SIZE"1B"
VOLTAGE"0";
"A\NAC"9;
%"CAP"
"1","(-650,1900)","0","mstr_discrete","I38";
;
ROOM"SB_DECOUPLING"
CDS_LOCATION"C7A32"
$SEC"1"
CDS_SEC"1"
BOM_COST"SB"
CDS_LIB"mstr_discrete"
MATERIAL"X6S"
VOLTAGE"4V"
PACK_TYPE"0805"
TOLERANCE"20%"
VALUE"47UF"
PART_NUMBER"C95333-006"
LOCATION"C7A32";
"A"
$PN"1"10;
"B"
$PN"2"11;
%"PVNN_PCH_STBY"
"1","(-875,2200)","0","mstr_symbols","I39";
;
HDL_POWER"PVNN_PCH_STBY"
ROOM"SB_DECOUPLING"
BODY_TYPE"PLUMBING"
BOM_COST"SB"
CDS_LIB"mstr_symbols"
VOLTAGE"1.0V";
"G\NAC"10;
%"CAP_A"
"1","(1450,4475)","0","dev_discrete","I4";
;
ROOM"SB_DECOUPLING"
$SEC"1"
CDS_SEC"1"
CDS_LIB"dev_discrete"
BOM_COST"SB"
CDS_LOCATION"C3L27"
MATERIAL"X6S"
VOLTAGE"4V"
PACK_TYPE"0603V"
TOLERANCE"20%"
VALUE"22.0UF"
PART_NUMBER"E15431-004"
LOCATION"C3L27";
"B"
$PN"2"1;
"A"
$PN"1"13;
%"CAP"
"1","(-1100,1900)","0","mstr_discrete","I40";
;
ROOM"SB_DECOUPLING"
CDS_LOCATION"C7A31"
$SEC"1"
CDS_SEC"1"
BOM_COST"SB"
CDS_LIB"mstr_discrete"
MATERIAL"X6S"
VOLTAGE"4V"
PACK_TYPE"0805"
TOLERANCE"20%"
VALUE"47UF"
PART_NUMBER"C95333-006"
LOCATION"C7A31";
"A"
$PN"1"10;
"B"
$PN"2"11;
%"GND"
"1","(-875,1525)","0","mstr_symbols","I41";
;
HDL_POWER"GND"
ROOM"SB_DECOUPLING"
BODY_TYPE"PLUMBING"
BOM_COST"SB"
CDS_LIB"mstr_symbols"
SIZE"1B"
VOLTAGE"0.0V";
"A\NAC"11;
%"CAP_A"
"1","(-2225,4050)","0","dev_discrete","I42";
;
ROOM"SB_DECOUPLING"
$SEC"1"
CDS_SEC"1"
CDS_LIB"dev_discrete"
BOM_COST"SB"
CDS_LOCATION"C3N18"
MATERIAL"X6S"
VOLTAGE"6.3V"
PACK_TYPE"0402V"
TOLERANCE"10%"
VALUE"1.0UF"
PART_NUMBER"D97712-004"
LOCATION"C3N18";
"B"
$PN"2"8;
"A"
$PN"1"12;
%"CAP_A"
"1","(-2625,4050)","0","dev_discrete","I43";
;
ROOM"SB_DECOUPLING"
$SEC"1"
CDS_SEC"1"
CDS_LIB"dev_discrete"
BOM_COST"SB"
CDS_LOCATION"C3N2"
MATERIAL"X6S"
VOLTAGE"6.3V"
PACK_TYPE"0402V"
TOLERANCE"10%"
VALUE"1.0UF"
PART_NUMBER"D97712-004"
LOCATION"C3N2";
"B"
$PN"2"8;
"A"
$PN"1"12;
%"CAP_A"
"1","(-2200,3025)","0","dev_discrete","I44";
;
ROOM"SB_DECOUPLING"
$SEC"1"
CDS_SEC"1"
CDS_LIB"dev_discrete"
BOM_COST"SB"
CDS_LOCATION"C3N6"
MATERIAL"X6S"
VOLTAGE"6.3V"
PACK_TYPE"0402V"
TOLERANCE"10%"
VALUE"1.0UF"
PART_NUMBER"D97712-004"
LOCATION"C3N6";
"B"
$PN"2"9;
"A"
$PN"1"14;
%"CAP_A"
"1","(-2600,3025)","0","dev_discrete","I45";
;
ROOM"SB_DECOUPLING"
$SEC"1"
CDS_SEC"1"
CDS_LIB"dev_discrete"
BOM_COST"SB"
CDS_LOCATION"C3N17"
MATERIAL"X6S"
VOLTAGE"6.3V"
PACK_TYPE"0402V"
TOLERANCE"10%"
VALUE"1.0UF"
PART_NUMBER"D97712-004"
LOCATION"C3N17";
"B"
$PN"2"9;
"A"
$PN"1"14;
%"CAP_A"
"1","(-3000,4050)","0","dev_discrete","I46";
;
ROOM"SB_DECOUPLING"
$SEC"1"
CDS_SEC"1"
CDS_LIB"dev_discrete"
BOM_COST"SB"
CDS_LOCATION"C3N4"
MATERIAL"X6S"
VOLTAGE"6.3V"
PACK_TYPE"0402V"
TOLERANCE"10%"
VALUE"1.0UF"
PART_NUMBER"D97712-004"
LOCATION"C3N4";
"B"
$PN"2"8;
"A"
$PN"1"12;
%"PVNN_PCH_STBY"
"1","(-3225,4300)","0","mstr_symbols","I47";
;
HDL_POWER"PVNN_PCH_STBY"
ROOM"SB_DECOUPLING"
BODY_TYPE"PLUMBING"
BOM_COST"SB"
CDS_LIB"mstr_symbols"
VOLTAGE"1.0V";
"G\NAC"12;
%"CAP_A"
"1","(-3400,4050)","0","dev_discrete","I48";
;
ROOM"SB_DECOUPLING"
$SEC"1"
CDS_SEC"1"
CDS_LIB"dev_discrete"
BOM_COST"SB"
CDS_LOCATION"C3N5"
MATERIAL"X6S"
VOLTAGE"6.3V"
PACK_TYPE"0402V"
TOLERANCE"10%"
VALUE"1.0UF"
PART_NUMBER"D97712-004"
LOCATION"C3N5";
"B"
$PN"2"8;
"A"
$PN"1"12;
%"CAP_A"
"1","(-2975,3025)","0","dev_discrete","I49";
;
ROOM"SB_DECOUPLING"
$SEC"1"
CDS_SEC"1"
CDS_LIB"dev_discrete"
BOM_COST"SB"
CDS_LOCATION"C3N15"
MATERIAL"X6S"
VOLTAGE"6.3V"
PACK_TYPE"0402V"
TOLERANCE"10%"
VALUE"1.0UF"
PART_NUMBER"D97712-004"
LOCATION"C3N15";
"B"
$PN"2"9;
"A"
$PN"1"14;
%"PVNN_PCH_STBY"
"1","(1350,4725)","0","mstr_symbols","I5";
;
HDL_POWER"PVNN_PCH_STBY"
ROOM"SB_DECOUPLING"
BODY_TYPE"PLUMBING"
BOM_COST"SB"
CDS_LIB"mstr_symbols"
VOLTAGE"1.0V";
"G\NAC"13;
%"PVNN_PCH_STBY"
"1","(-3200,3275)","0","mstr_symbols","I50";
;
HDL_POWER"PVNN_PCH_STBY"
ROOM"SB_DECOUPLING"
BODY_TYPE"PLUMBING"
BOM_COST"SB"
CDS_LIB"mstr_symbols"
VOLTAGE"1.0V";
"G\NAC"14;
%"CAP_A"
"1","(-3375,3025)","0","dev_discrete","I51";
;
ROOM"SB_DECOUPLING"
$SEC"1"
CDS_SEC"1"
CDS_LIB"dev_discrete"
BOM_COST"SB"
CDS_LOCATION"C3N20"
MATERIAL"X6S"
VOLTAGE"6.3V"
PACK_TYPE"0402V"
TOLERANCE"10%"
VALUE"1.0UF"
PART_NUMBER"D97712-004"
LOCATION"C3N20";
"B"
$PN"2"9;
"A"
$PN"1"14;
%"CAP_A"
"1","(-2550,1925)","0","dev_discrete","I52";
;
ROOM"SB_DECOUPLING"
$SEC"1"
CDS_SEC"1"
CDS_LIB"dev_discrete"
BOM_COST"SB"
CDS_LOCATION"C3L23"
MATERIAL"X6S"
VOLTAGE"4V"
PACK_TYPE"0603V"
TOLERANCE"20%"
VALUE"22.0UF"
PART_NUMBER"E15431-004"
LOCATION"C3L23";
"B"
$PN"2"16;
"A"
$PN"1"15;
%"PVNN_PCH_STBY"
"1","(-3150,2200)","0","mstr_symbols","I53";
;
HDL_POWER"PVNN_PCH_STBY"
ROOM"SB_DECOUPLING"
BODY_TYPE"PLUMBING"
BOM_COST"SB"
CDS_LIB"mstr_symbols"
VOLTAGE"1.0V";
"G\NAC"15;
%"CAP_A"
"1","(-2950,1925)","0","dev_discrete","I54";
;
ROOM"SB_DECOUPLING"
$SEC"1"
CDS_SEC"1"
CDS_LIB"dev_discrete"
BOM_COST"SB"
CDS_LOCATION"C3L22"
MATERIAL"X6S"
VOLTAGE"4V"
PACK_TYPE"0603V"
TOLERANCE"20%"
VALUE"22.0UF"
PART_NUMBER"E15431-004"
LOCATION"C3L22";
"B"
$PN"2"16;
"A"
$PN"1"15;
%"GND"
"1","(-3100,1600)","0","mstr_symbols","I55";
;
HDL_POWER"GND"
ROOM"SB_DECOUPLING"
BODY_TYPE"PLUMBING"
BOM_COST"SB"
SIZE"1B"
CDS_LIB"mstr_symbols"
VOLTAGE"0.0V";
"A\NAC"16;
%"CAP_A"
"1","(-3425,1925)","0","dev_discrete","I56";
;
ROOM"SB_DECOUPLING"
$SEC"1"
CDS_SEC"1"
CDS_LIB"dev_discrete"
BOM_COST"SB"
CDS_LOCATION"C3L24"
MATERIAL"X6S"
VOLTAGE"4V"
PACK_TYPE"0603V"
TOLERANCE"20%"
VALUE"22.0UF"
PART_NUMBER"E15431-004"
LOCATION"C3L24";
"B"
$PN"2"16;
"A"
$PN"1"15;
%"CAP_A"
"1","(1075,4475)","0","dev_discrete","I6";
;
ROOM"SB_DECOUPLING"
$SEC"1"
CDS_SEC"1"
CDS_LIB"dev_discrete"
BOM_COST"SB"
CDS_LOCATION"C3M6"
MATERIAL"X6S"
VOLTAGE"4V"
PACK_TYPE"0603V"
TOLERANCE"20%"
VALUE"22.0UF"
PART_NUMBER"E15431-004"
LOCATION"C3M6";
"B"
$PN"2"1;
"A"
$PN"1"13;
%"CAP_A"
"1","(2550,3500)","0","dev_discrete","I7";
;
ROOM"SB_DECOUPLING"
$SEC"1"
CDS_SEC"1"
CDS_LIB"dev_discrete"
BOM_COST"SB"
CDS_LOCATION"C7C9"
MATERIAL"X6S"
VOLTAGE"4V"
PACK_TYPE"0603V"
TOLERANCE"20%"
VALUE"22.0UF"
PART_NUMBER"E15431-004"
LOCATION"C7C9";
"B"
$PN"2"3;
"A"
$PN"1"2;
%"CAP_A"
"1","(2600,2525)","0","dev_discrete","I8";
;
ROOM"SB_DECOUPLING"
$SEC"1"
CDS_SEC"1"
CDS_LIB"dev_discrete"
BOM_COST"SB"
CDS_LOCATION"C3N27"
MATERIAL"X6S"
VOLTAGE"4V"
PACK_TYPE"0603V"
TOLERANCE"20%"
VALUE"22.0UF"
PART_NUMBER"E15431-004"
LOCATION"C3N27";
"B"
$PN"2"5;
"A"
$PN"1"4;
%"CAP_A"
"1","(2225,2525)","0","dev_discrete","I9";
;
ROOM"SB_DECOUPLING"
$SEC"1"
CDS_SEC"1"
CDS_LIB"dev_discrete"
BOM_COST"SB"
CDS_LOCATION"C3N30"
MATERIAL"X6S"
VOLTAGE"4V"
PACK_TYPE"0603V"
TOLERANCE"20%"
VALUE"22.0UF"
PART_NUMBER"E15431-004"
LOCATION"C3N30";
"B"
$PN"2"5;
"A"
$PN"1"4;
END.
